(kicad_pcb
	(version 20240108)
	(generator "pcbnew")
	(generator_version "8.0")
	(general
		(thickness 1.586)
		(legacy_teardrops no)
	)
	(paper "A4")
	(title_block
		(title "GMSL Serializer")
		(date "2024-11-27")
		(rev "1.1.1")
		(company "Antmicro Ltd")
		(comment 1 "www.antmicro.com")
		(comment 9 "footprints 101-104 of 117")
	)
	(layers
		(0 "F.Cu" signal)
		(1 "In1.Cu" power)
		(2 "In2.Cu" power)
		(31 "B.Cu" signal)
		(32 "B.Adhes" user "B.Adhesive")
		(33 "F.Adhes" user "F.Adhesive")
		(34 "B.Paste" user)
		(35 "F.Paste" user)
		(36 "B.SilkS" user "B.Silkscreen")
		(37 "F.SilkS" user "F.Silkscreen")
		(38 "B.Mask" user)
		(39 "F.Mask" user)
		(40 "Dwgs.User" user "User.Drawings")
		(41 "Cmts.User" user "User.Comments")
		(42 "Eco1.User" user "User.Eco1")
		(43 "Eco2.User" user "User.Eco2")
		(44 "Edge.Cuts" user)
		(45 "Margin" user)
		(46 "B.CrtYd" user "B.Courtyard")
		(47 "F.CrtYd" user "F.Courtyard")
		(48 "B.Fab" user)
		(49 "F.Fab" user)
	)
	(footprint "antmicro-footprints:DFN-10_2.5x1mm"
		(layer "F.Cu")
		(at 130.5 106.099)
		(property "Reference" "D3"
			(at -0.8 -1.699 0)
			(layer "F.SilkS")
			(effects
				(font
					(size 0.7 0.7)
					(thickness 0.15)
				)
				(justify left bottom)
			)
		)
		(property "Value" "PESD4USB5U-TTS"
			(at 2.032 1.524 0)
			(layer "F.Fab")
			(effects
				(font
					(size 0.7 0.7)
					(thickness 0.15)
				)
				(justify left bottom)
			)
		)
		(property "Footprint" "antmicro-footprints:DFN-10_2.5x1mm"
			(at 0 0 0)
			(layer "F.Fab")
			(hide yes)
			(effects
				(font
					(size 1.27 1.27)
					(thickness 0.15)
				)
			)
		)
		(property "Datasheet" "https://assets.nexperia.com/documents/data-sheet/PESD4USB5U-TTS.pdf"
			(at 0 0 0)
			(layer "F.Fab")
			(hide yes)
			(effects
				(font
					(size 1.27 1.27)
					(thickness 0.15)
				)
			)
		)
		(property "Author" "Antmicro"
			(at 0 0 0)
			(layer "F.Fab")
			(hide yes)
			(effects
				(font
					(size 1 1)
					(thickness 0.15)
				)
			)
		)
		(property "License" "Apache-2.0"
			(at 0 0 0)
			(layer "F.Fab")
			(hide yes)
			(effects
				(font
					(size 1 1)
					(thickness 0.15)
				)
			)
		)
		(property "MPN" "PESD4USB5U-TTS"
			(at 0 0 0)
			(layer "F.Fab")
			(hide yes)
			(effects
				(font
					(size 1 1)
					(thickness 0.15)
				)
			)
		)
		(property "Manufacturer" "Nexperia"
			(at 0 0 0)
			(layer "F.Fab")
			(hide yes)
			(effects
				(font
					(size 1 1)
					(thickness 0.15)
				)
			)
		)
		(sheetname "CSI Connector")
		(sheetfile "CSI.kicad_sch")
		(attr smd)
		(fp_line
			(start -0.4 1.4)
			(end 0.4 1.4)
			(stroke
				(width 0.15)
				(type solid)
			)
			(layer "F.SilkS")
		)
		(fp_line
			(start 0.4 -1.4)
			(end -0.4 -1.4)
			(stroke
				(width 0.15)
				(type solid)
			)
			(layer "F.SilkS")
		)
		(fp_circle
			(center -0.762 -1.27)
			(end -0.712 -1.27)
			(stroke
				(width 0.15)
				(type solid)
			)
			(fill solid)
			(layer "F.SilkS")
		)
		(fp_rect
			(start -0.85 -1.6)
			(end 0.85 1.6)
			(stroke
				(width 0.05)
				(type solid)
			)
			(fill none)
			(layer "F.CrtYd")
		)
		(fp_line
			(start -0.5 -0.9)
			(end -0.5 1.25)
			(stroke
				(width 0.15)
				(type solid)
			)
			(layer "F.Fab")
		)
		(fp_line
			(start -0.5 1.25)
			(end 0.5 1.25)
			(stroke
				(width 0.15)
				(type solid)
			)
			(layer "F.Fab")
		)
		(fp_line
			(start -0.15 -1.25)
			(end -0.5 -0.9)
			(stroke
				(width 0.15)
				(type solid)
			)
			(layer "F.Fab")
		)
		(fp_line
			(start 0.5 -1.25)
			(end -0.15 -1.25)
			(stroke
				(width 0.15)
				(type solid)
			)
			(layer "F.Fab")
		)
		(fp_line
			(start 0.5 1.25)
			(end 0.5 -1.25)
			(stroke
				(width 0.15)
				(type solid)
			)
			(layer "F.Fab")
		)
		(fp_text user "License: Apache-2.0"
			(at -0.95 5.924 0)
			(layer "F.Fab")
			(hide yes)
			(effects
				(font
					(size 0.7 0.7)
					(thickness 0.15)
				)
				(justify left bottom)
			)
		)
		(fp_text user "${REFERENCE}"
			(at -0.95 3.524 0)
			(layer "F.Fab")
			(hide yes)
			(effects
				(font
					(size 0.7 0.7)
					(thickness 0.15)
				)
				(justify left bottom)
			)
		)
		(fp_text user "Author: Antmicro"
			(at -0.95 4.724 0)
			(layer "F.Fab")
			(hide yes)
			(effects
				(font
					(size 0.7 0.7)
					(thickness 0.15)
				)
				(justify left bottom)
			)
		)
		(pad "1" smd roundrect
			(at -0.425 -1 270)
			(size 0.2 0.6)
			(layers "F.Cu" "F.Paste" "F.Mask")
			(roundrect_rratio 0.25)
			(net 38 "/CSI Connector/GPIO3")
			(pinfunction "1")
			(pintype "passive")
			(solder_mask_margin 0.05)
		)
		(pad "2" smd roundrect
			(at -0.425 -0.5 270)
			(size 0.2 0.6)
			(layers "F.Cu" "F.Paste" "F.Mask")
			(roundrect_rratio 0.25)
			(net 39 "/CSI Connector/GPIO4_1V8")
			(pinfunction "2")
			(pintype "passive")
			(solder_mask_margin 0.05)
		)
		(pad "3" smd roundrect
			(at -0.425 0 270)
			(size 0.4 0.6)
			(layers "F.Cu" "F.Paste" "F.Mask")
			(roundrect_rratio 0.25)
			(net 1 "GND")
			(pinfunction "3")
			(pintype "passive")
			(solder_mask_margin 0.05)
		)
		(pad "4" smd roundrect
			(at -0.425 0.5 270)
			(size 0.2 0.6)
			(layers "F.Cu" "F.Paste" "F.Mask")
			(roundrect_rratio 0.25)
			(net 91 "unconnected-(D3-Pad4)")
			(pinfunction "4")
			(pintype "passive")
			(solder_mask_margin 0.05)
		)
		(pad "5" smd roundrect
			(at -0.425 1 270)
			(size 0.2 0.6)
			(layers "F.Cu" "F.Paste" "F.Mask")
			(roundrect_rratio 0.25)
			(net 92 "unconnected-(D3-Pad5)")
			(pinfunction "5")
			(pintype "passive")
			(solder_mask_margin 0.05)
		)
		(pad "6" smd roundrect
			(at 0.425 1 270)
			(size 0.2 0.6)
			(layers "F.Cu" "F.Paste" "F.Mask")
			(roundrect_rratio 0.25)
			(net 92 "unconnected-(D3-Pad5)")
			(pinfunction "6")
			(pintype "passive")
			(solder_mask_margin 0.05)
		)
		(pad "7" smd roundrect
			(at 0.425 0.5 270)
			(size 0.2 0.6)
			(layers "F.Cu" "F.Paste" "F.Mask")
			(roundrect_rratio 0.25)
			(net 91 "unconnected-(D3-Pad4)")
			(pinfunction "7")
			(pintype "passive")
			(solder_mask_margin 0.05)
		)
		(pad "8" smd roundrect
			(at 0.425 0 270)
			(size 0.4 0.6)
			(layers "F.Cu" "F.Paste" "F.Mask")
			(roundrect_rratio 0.25)
			(net 1 "GND")
			(pinfunction "8")
			(pintype "passive")
			(solder_mask_margin 0.05)
		)
		(pad "9" smd roundrect
			(at 0.425 -0.5 270)
			(size 0.2 0.6)
			(layers "F.Cu" "F.Paste" "F.Mask")
			(roundrect_rratio 0.25)
			(net 39 "/CSI Connector/GPIO4_1V8")
			(pinfunction "9")
			(pintype "passive")
			(solder_mask_margin 0.05)
		)
		(pad "10" smd roundrect
			(at 0.425 -1 270)
			(size 0.2 0.6)
			(layers "F.Cu" "F.Paste" "F.Mask")
			(roundrect_rratio 0.25)
			(net 38 "/CSI Connector/GPIO3")
			(pinfunction "10")
			(pintype "passive")
			(solder_mask_margin 0.05)
		)
	)
	(footprint "antmicro-footprints:R_0603_1608Metric"
		(layer "F.Cu")
		(at 136.929 88.647 -90)
		(descr "Resistor SMD 0603")
		(tags "resistor SMD 0603")
		(property "Reference" "R13"
			(at -0.477 -1.481 90)
			(layer "F.SilkS")
			(effects
				(font
					(size 0.7 0.7)
					(thickness 0.15)
				)
				(justify right bottom)
			)
		)
		(property "Value" "R_0R_22.4A_0603"
			(at 0 1.6 90)
			(layer "F.Fab")
			(effects
				(font
					(size 0.7 0.7)
					(thickness 0.15)
				)
				(justify right bottom)
			)
		)
		(property "Footprint" "antmicro-footprints:R_0603_1608Metric"
			(at 0 0 -90)
			(layer "F.Fab")
			(hide yes)
			(effects
				(font
					(size 1.27 1.27)
					(thickness 0.15)
				)
			)
		)
		(property "Datasheet" "https://fscdn.rohm.com/en/products/databook/datasheet/passive/resistor/chip_resistor/pmr-jpw-e.pdf"
			(at 0 0 -90)
			(layer "F.Fab")
			(hide yes)
			(effects
				(font
					(size 1.27 1.27)
					(thickness 0.15)
				)
			)
		)
		(property "Author" "Antmicro"
			(at 50.202 227.196 0)
			(layer "F.Fab")
			(hide yes)
			(effects
				(font
					(size 1 1)
					(thickness 0.15)
				)
			)
		)
		(property "License" "Apache-2.0"
			(at 50.202 227.196 0)
			(layer "F.Fab")
			(hide yes)
			(effects
				(font
					(size 1 1)
					(thickness 0.15)
				)
			)
		)
		(property "MPN" "PMR03EZPJ000"
			(at 50.202 227.196 0)
			(layer "F.Fab")
			(hide yes)
			(effects
				(font
					(size 1 1)
					(thickness 0.15)
				)
			)
		)
		(property "Manufacturer" "ROHM Semiconductor"
			(at 50.202 227.196 0)
			(layer "F.Fab")
			(hide yes)
			(effects
				(font
					(size 1 1)
					(thickness 0.15)
				)
			)
		)
		(property "Max. Curr." "22.4A"
			(at 50.202 227.196 0)
			(layer "F.Fab")
			(hide yes)
			(effects
				(font
					(size 1 1)
					(thickness 0.15)
				)
			)
		)
		(property "Tolerance" "template_tolerance"
			(at 50.202 227.196 0)
			(layer "F.Fab")
			(hide yes)
			(effects
				(font
					(size 1 1)
					(thickness 0.15)
				)
			)
		)
		(property "Val" "0R"
			(at 50.202 227.196 0)
			(layer "F.Fab")
			(hide yes)
			(effects
				(font
					(size 1 1)
					(thickness 0.15)
				)
			)
		)
		(sheetname "Supply")
		(sheetfile "supply.kicad_sch")
		(attr smd)
		(fp_line
			(start -0.15 0.4)
			(end 0.15 0.4)
			(stroke
				(width 0.15)
				(type solid)
			)
			(layer "F.SilkS")
		)
		(fp_line
			(start -0.15 -0.4)
			(end 0.15 -0.4)
			(stroke
				(width 0.15)
				(type solid)
			)
			(layer "F.SilkS")
		)
		(fp_rect
			(start -1.25 -0.65)
			(end 1.25 0.65)
			(stroke
				(width 0.05)
				(type solid)
			)
			(fill none)
			(layer "F.CrtYd")
		)
		(fp_rect
			(start -0.8 -0.4)
			(end 0.8 0.4)
			(stroke
				(width 0.15)
				(type solid)
			)
			(fill none)
			(layer "F.Fab")
		)
		(fp_text user "License: Apache-2.0"
			(at -1.25 5.9 90)
			(layer "F.Fab")
			(hide yes)
			(effects
				(font
					(size 0.7 0.7)
					(thickness 0.15)
				)
				(justify right bottom)
			)
		)
		(fp_text user "Author: Antmicro"
			(at -1.25 4.9 90)
			(layer "F.Fab")
			(hide yes)
			(effects
				(font
					(size 0.7 0.7)
					(thickness 0.15)
				)
				(justify right bottom)
			)
		)
		(fp_text user "${REFERENCE}"
			(at -1.25 3.898 90)
			(layer "F.Fab")
			(hide yes)
			(effects
				(font
					(size 0.7 0.7)
					(thickness 0.15)
				)
				(justify right bottom)
			)
		)
		(pad "1" smd roundrect
			(at -0.7 0 270)
			(size 0.8 1)
			(layers "F.Cu" "F.Paste" "F.Mask")
			(roundrect_rratio 0.2)
			(net 7 "/Supply/OUT_5V")
			(pintype "passive")
		)
		(pad "2" smd roundrect
			(at 0.7 0 270)
			(size 0.8 1)
			(layers "F.Cu" "F.Paste" "F.Mask")
			(roundrect_rratio 0.2)
			(net 9 "+5V")
			(pintype "passive")
		)
	)
	(footprint "antmicro-footprints:LED_0603_1608Metric_G"
		(layer "F.Cu")
		(at 147.75 115.75 -90)
		(descr "LED SMD 0603 Green")
		(tags "LED SMD 0603 Green")
		(property "Reference" "D8"
			(at -2.25 1.125 90)
			(layer "F.SilkS")
			(effects
				(font
					(size 0.7 0.7)
					(thickness 0.15)
				)
				(justify right bottom)
			)
		)
		(property "Value" "LED_G_0603_LTST-C190GKT"
			(at -0.001 1.599 90)
			(layer "F.Fab")
			(effects
				(font
					(size 0.7 0.7)
					(thickness 0.15)
				)
				(justify right bottom)
			)
		)
		(property "Footprint" "antmicro-footprints:LED_0603_1608Metric_G"
			(at 0 0 -90)
			(layer "F.Fab")
			(hide yes)
			(effects
				(font
					(size 1.27 1.27)
					(thickness 0.15)
				)
			)
		)
		(property "Datasheet" "https://media.digikey.com/pdf/Data%20Sheets/Lite-On%20PDFs/LTST-C190GKT.pdf"
			(at 0 0 -90)
			(layer "F.Fab")
			(hide yes)
			(effects
				(font
					(size 1.27 1.27)
					(thickness 0.15)
				)
			)
		)
		(property "Author" "Antmicro"
			(at 32 263.5 0)
			(layer "F.Fab")
			(hide yes)
			(effects
				(font
					(size 1 1)
					(thickness 0.15)
				)
			)
		)
		(property "Color" "Green"
			(at 32 263.5 0)
			(layer "F.Fab")
			(hide yes)
			(effects
				(font
					(size 1 1)
					(thickness 0.15)
				)
			)
		)
		(property "License" "Apache-2.0"
			(at 32 263.5 0)
			(layer "F.Fab")
			(hide yes)
			(effects
				(font
					(size 1 1)
					(thickness 0.15)
				)
			)
		)
		(property "MPN" "LTST-C190GKT"
			(at 32 263.5 0)
			(layer "F.Fab")
			(hide yes)
			(effects
				(font
					(size 1 1)
					(thickness 0.15)
				)
			)
		)
		(property "Manufacturer" "Lite-On"
			(at 32 263.5 0)
			(layer "F.Fab")
			(hide yes)
			(effects
				(font
					(size 1 1)
					(thickness 0.15)
				)
			)
		)
		(property "VSD_class" "LED"
			(at 32 263.5 0)
			(layer "F.Fab")
			(hide yes)
			(effects
				(font
					(size 1 1)
					(thickness 0.15)
				)
			)
		)
		(sheetname "Supply")
		(sheetfile "supply.kicad_sch")
		(attr smd)
		(fp_line
			(start 0.22 0.35)
			(end -0.22 0.35)
			(stroke
				(width 0.15)
				(type solid)
			)
			(layer "F.SilkS")
		)
		(fp_line
			(start -0.094672 0.201008)
			(end -0.094672 -0.198992)
			(stroke
				(width 0.1)
				(type solid)
			)
			(layer "F.SilkS")
		)
		(fp_line
			(start 0.105328 0.201008)
			(end -0.094672 0.001008)
			(stroke
				(width 0.1)
				(type solid)
			)
			(layer "F.SilkS")
		)
		(fp_line
			(start 0.105328 0.201008)
			(end 0.105328 -0.198992)
			(stroke
				(width 0.1)
				(type solid)
			)
			(layer "F.SilkS")
		)
		(fp_line
			(start -0.094672 0.001008)
			(end -0.24 0.001008)
			(stroke
				(width 0.1)
				(type solid)
			)
			(layer "F.SilkS")
		)
		(fp_line
			(start -0.094672 0.001008)
			(end 0.105328 -0.198992)
			(stroke
				(width 0.1)
				(type solid)
			)
			(layer "F.SilkS")
		)
		(fp_line
			(start 0.105328 0.001008)
			(end 0.24 0.001)
			(stroke
				(width 0.1)
				(type solid)
			)
			(layer "F.SilkS")
		)
		(fp_line
			(start -1.18 -0.319)
			(end -1.18 0.321)
			(stroke
				(width 0.15)
				(type solid)
			)
			(layer "F.SilkS")
		)
		(fp_line
			(start 0.22 -0.35)
			(end -0.22 -0.35)
			(stroke
				(width 0.15)
				(type solid)
			)
			(layer "F.SilkS")
		)
		(fp_rect
			(start 1.25 0.65)
			(end -1.25 -0.65)
			(stroke
				(width 0.05)
				(type solid)
			)
			(fill none)
			(layer "F.CrtYd")
		)
		(fp_line
			(start -0.199 0.2)
			(end -0.199 0.1)
			(stroke
				(width 0.15)
				(type solid)
			)
			(layer "F.Fab")
		)
		(fp_line
			(start 0.201 0.2)
			(end 0.201 0)
			(stroke
				(width 0.15)
				(type solid)
			)
			(layer "F.Fab")
		)
		(fp_line
			(start -0.199 0)
			(end -0.597 0)
			(stroke
				(width 0.15)
				(type solid)
			)
			(layer "F.Fab")
		)
		(fp_line
			(start -0.101 0)
			(end 0.201 0.2)
			(stroke
				(width 0.15)
				(type solid)
			)
			(layer "F.Fab")
		)
		(fp_line
			(start 0.201 0)
			(end 0.201 -0.202)
			(stroke
				(width 0.15)
				(type solid)
			)
			(layer "F.Fab")
		)
		(fp_line
			(start 0.599 0)
			(end 0.201 0)
			(stroke
				(width 0.15)
				(type solid)
			)
			(layer "F.Fab")
		)
		(fp_line
			(start -0.199 -0.202)
			(end -0.199 0.1)
			(stroke
				(width 0.15)
				(type solid)
			)
			(layer "F.Fab")
		)
		(fp_line
			(start 0.201 -0.202)
			(end -0.101 0)
			(stroke
				(width 0.15)
				(type solid)
			)
			(layer "F.Fab")
		)
		(fp_rect
			(start 0.848 0.4)
			(end -0.85 -0.402)
			(stroke
				(width 0.15)
				(type solid)
			)
			(fill none)
			(layer "F.Fab")
		)
		(fp_text user "License: Apache-2.0"
			(at -1.4224 3.599 90)
			(layer "F.Fab")
			(hide yes)
			(effects
				(font
					(size 0.7 0.7)
					(thickness 0.15)
				)
				(justify right bottom)
			)
		)
		(fp_text user "${REFERENCE}"
			(at -1.4224 5.999 90)
			(layer "F.Fab")
			(hide yes)
			(effects
				(font
					(size 0.7 0.7)
					(thickness 0.15)
				)
				(justify right bottom)
			)
		)
		(fp_text user "Author: Antmicro"
			(at -1.4224 4.799 90)
			(layer "F.Fab")
			(hide yes)
			(effects
				(font
					(size 0.7 0.7)
					(thickness 0.15)
				)
				(justify right bottom)
			)
		)
		(pad "1" smd roundrect
			(at -0.7 0 90)
			(size 0.8 1)
			(layers "F.Cu" "F.Paste" "F.Mask")
			(roundrect_rratio 0.2)
			(net 73 "Net-(D8-C)")
			(pinfunction "C")
			(pintype "passive")
		)
		(pad "2" smd roundrect
			(at 0.7 0 90)
			(size 0.8 1)
			(layers "F.Cu" "F.Paste" "F.Mask")
			(roundrect_rratio 0.2)
			(net 74 "Net-(D8-A)")
			(pinfunction "A")
			(pintype "passive")
		)
	)
	(footprint "antmicro-footprints:MP_Pad6mm_Drill3mm"
		(layer "F.Cu")
		(at 163.15 81.35)
		(property "Reference" "MP2"
			(at 0 -3.2 0)
			(layer "F.SilkS")
			(hide yes)
			(effects
				(font
					(size 0.7 0.7)
					(thickness 0.15)
				)
				(justify left bottom)
			)
		)
		(property "Value" "MP_Pad6mm_Drill3mm"
			(at 0 3.9 0)
			(layer "F.Fab")
			(effects
				(font
					(size 0.7 0.7)
					(thickness 0.15)
				)
				(justify left bottom)
			)
		)
		(property "Footprint" "antmicro-footprints:MP_Pad6mm_Drill3mm"
			(at 0 0 0)
			(layer "F.Fab")
			(hide yes)
			(effects
				(font
					(size 1.27 1.27)
					(thickness 0.15)
				)
			)
		)
		(property "Author" "Antmicro"
			(at 0 0 0)
			(layer "F.Fab")
			(hide yes)
			(effects
				(font
					(size 1 1)
					(thickness 0.15)
				)
			)
		)
		(property "License" "Apache-2.0"
			(at 0 0 0)
			(layer "F.Fab")
			(hide yes)
			(effects
				(font
					(size 1 1)
					(thickness 0.15)
				)
			)
		)
		(sheetname "Root")
		(sheetfile "gmsl-serializer.kicad_sch")
		(attr exclude_from_pos_files exclude_from_bom)
		(fp_circle
			(center 0 0)
			(end 3.25 0)
			(stroke
				(width 0.05)
				(type default)
			)
			(fill none)
			(layer "F.CrtYd")
		)
		(fp_text user "License: Apache-2.0"
			(at -0.178 8.425 0)
			(layer "F.Fab")
			(hide yes)
			(effects
				(font
					(size 0.7 0.7)
					(thickness 0.15)
				)
				(justify left bottom)
			)
		)
		(fp_text user "Author: Antmicro"
			(at -0.178 7.225 0)
			(layer "F.Fab")
			(hide yes)
			(effects
				(font
					(size 0.7 0.7)
					(thickness 0.15)
				)
				(justify left bottom)
			)
		)
		(fp_text user "${REFERENCE}"
			(at -0.178 6.025 0)
			(layer "F.Fab")
			(hide yes)
			(effects
				(font
					(size 0.7 0.7)
					(thickness 0.15)
				)
				(justify left bottom)
			)
		)
		(pad "1" thru_hole circle
			(at 0 0)
			(size 6 6)
			(drill 3)
			(layers "*.Cu" "*.Mask")
			(remove_unused_layers no)
			(net 1 "GND")
			(pintype "passive")
			(solder_paste_margin_ratio -1)
		)
	)
)
